# S9S_MB_2U (Grand Teton) — schematic netlist excerpt (pin names and nets, part order shuffled) for the footprints in the layout excerpt that follows; sources: Cadence DE-HDL packaged netlist, KiCad conversion of 03242023_DA0F0TMBIJ0_F0T_Motherboard_J_brd_V01_OCP.brd

PC402  Q_CAP  100NF 50V 10% X7R  pkg C0402  page 289 : A = SW_PVCCFA_EHV_FIVRA_CPU1_BOOT2_ ; B = SW_PVCCFA_EHV_FIVRA_CPU1_BOOTR2
PC2180  Q_CAPP  560UF 2.5V 20% OSCON  pkg THLF  page 276 : A = PVCCFA_EHV_CPU0 ; B = GND
R754  Q_RES  10 1% CHIP  pkg 0402LF  page 132 : A = JTAG_DBP_TMS ; B = JTAG_DBP_TMS_PCH

(kicad_pcb
	(version 20260206)
	(generator "pcbnew")
	(generator_version "10.0")
	(general
		(thickness 1.6)
		(legacy_teardrops no)
	)
	(paper "A4")
	(title_block
		(title "03242023_DA0F0TMBIJ0_F0T_Motherboard_J_brd_V01_OCP.brd")
		(comment 1 "Grand Teton / footprints 2062-2064 of 6105")
	)
	(layers
		(0 "F.Cu" signal "TOP")
		(4 "In1.Cu" signal "GND")
		(6 "In2.Cu" signal "IN1")
		(8 "In3.Cu" signal "GND1")
		(10 "In4.Cu" signal "IN2")
		(12 "In5.Cu" signal "GND2")
		(14 "In6.Cu" signal "IN3")
		(16 "In7.Cu" signal "GND3")
		(18 "In8.Cu" signal "VCC")
		(20 "In9.Cu" signal "VCC1")
		(22 "In10.Cu" signal "GND4")
		(24 "In11.Cu" signal "IN4")
		(26 "In12.Cu" signal "GND5")
		(28 "In13.Cu" signal "IN5")
		(30 "In14.Cu" signal "GND6")
		(32 "In15.Cu" signal "IN6")
		(34 "In16.Cu" signal "GND7")
		(2 "B.Cu" signal "BOTTOM")
		(9 "F.Adhes" user "F.Adhesive")
		(11 "B.Adhes" user "B.Adhesive")
		(13 "F.Paste" user "Package Geometry/Pastemask Top")
		(15 "B.Paste" user "Package Geometry/Pastemask Bottom")
		(5 "F.SilkS" user "Ref Des/Silkscreen Top")
		(7 "B.SilkS" user "Ref Des/Silkscreen Bottom")
		(1 "F.Mask" user "Board Geometry/Soldermask Top")
		(3 "B.Mask" user "Board Geometry/Soldermask Bottom")
		(17 "Dwgs.User" user "User.Drawings")
		(19 "Cmts.User" user "User.Comments")
		(21 "Eco1.User" user "User.Eco1")
		(23 "Eco2.User" user "User.Eco2")
		(25 "Edge.Cuts" user "Board Geometry/Outline")
		(27 "Margin" user)
		(31 "F.CrtYd" user "Package Geometry/Place Bound Top")
		(29 "B.CrtYd" user "Package Geometry/Place Bound Bottom")
		(35 "F.Fab" user "Ref Des/Assembly Top")
		(33 "B.Fab" user "Ref Des/Assembly Bottom")
	)
	(footprint ""
		(layer "F.Cu")
		(at 52.759864 -358.20223 -90)
		(property "Reference" "PC402"
			(at 0 0 270)
			(layer "F.SilkS")
			(hide yes)
			(effects
				(font
					(size 1.27 1.27)
				)
			)
		)
		(property "Value" ""
			(at 0 0 270)
			(layer "F.Fab")
			(effects
				(font
					(size 1.27 1.27)
				)
			)
		)
		(duplicate_pad_numbers_are_jumpers no)
		(fp_line
			(start -0.7874 0.4064)
			(end -0.7874 -0.4064)
			(stroke
				(width 0.1524)
				(type default)
			)
			(layer "F.SilkS")
		)
		(fp_line
			(start 0.7874 0.4064)
			(end -0.7874 0.4064)
			(stroke
				(width 0.1524)
				(type default)
			)
			(layer "F.SilkS")
		)
		(fp_line
			(start -0.7874 -0.4064)
			(end 0.7874 -0.4064)
			(stroke
				(width 0.1524)
				(type default)
			)
			(layer "F.SilkS")
		)
		(fp_line
			(start 0.7874 -0.4064)
			(end 0.7874 0.4064)
			(stroke
				(width 0.1524)
				(type default)
			)
			(layer "F.SilkS")
		)
		(fp_line
			(start -0.67945 0.3048)
			(end -0.67945 -0.305054)
			(stroke
				(width 0.1)
				(type default)
			)
			(layer "F.Fab")
		)
		(fp_line
			(start -0.12065 0.3048)
			(end -0.67945 0.3048)
			(stroke
				(width 0.1)
				(type default)
			)
			(layer "F.Fab")
		)
		(fp_line
			(start 0.120396 0.3048)
			(end 0.120396 0.2794)
			(stroke
				(width 0.1)
				(type default)
			)
			(layer "F.Fab")
		)
		(fp_line
			(start 0.67945 0.3048)
			(end 0.120396 0.3048)
			(stroke
				(width 0.1)
				(type default)
			)
			(layer "F.Fab")
		)
		(fp_line
			(start -0.12065 0.2794)
			(end -0.12065 0.3048)
			(stroke
				(width 0.1)
				(type default)
			)
			(layer "F.Fab")
		)
		(fp_line
			(start 0.120396 0.2794)
			(end -0.12065 0.2794)
			(stroke
				(width 0.1)
				(type default)
			)
			(layer "F.Fab")
		)
		(fp_line
			(start -0.12065 -0.2794)
			(end 0.12065 -0.2794)
			(stroke
				(width 0.1)
				(type default)
			)
			(layer "F.Fab")
		)
		(fp_line
			(start 0.12065 -0.2794)
			(end 0.12065 -0.3048)
			(stroke
				(width 0.1)
				(type default)
			)
			(layer "F.Fab")
		)
		(fp_line
			(start 0.12065 -0.3048)
			(end 0.67945 -0.3048)
			(stroke
				(width 0.1)
				(type default)
			)
			(layer "F.Fab")
		)
		(fp_line
			(start 0.67945 -0.3048)
			(end 0.67945 0.3048)
			(stroke
				(width 0.1)
				(type default)
			)
			(layer "F.Fab")
		)
		(fp_line
			(start -0.67945 -0.305054)
			(end -0.12065 -0.305054)
			(stroke
				(width 0.1)
				(type default)
			)
			(layer "F.Fab")
		)
		(fp_line
			(start -0.12065 -0.305054)
			(end -0.12065 -0.2794)
			(stroke
				(width 0.1)
				(type default)
			)
			(layer "F.Fab")
		)
		(pad "1" smd circle
			(at -0.40005 0 270)
			(size 0 0)
			(layers "F.Cu" "F.Mask" "F.Paste")
			(net "SW_PVCCFA_EHV_FIVRA_CPU1_BOOT2_")
		)
		(pad "2" smd circle
			(at 0.40005 0 270)
			(size 0 0)
			(layers "F.Cu" "F.Mask" "F.Paste")
			(net "SW_PVCCFA_EHV_FIVRA_CPU1_BOOTR2")
		)
	)
	(footprint ""
		(layer "F.Cu")
		(at 367.411 -54.828948)
		(property "Reference" "R754"
			(at 0 0 0)
			(layer "F.SilkS")
			(hide yes)
			(effects
				(font
					(size 1.27 1.27)
				)
			)
		)
		(property "Value" ""
			(at 0 0 0)
			(layer "F.Fab")
			(effects
				(font
					(size 1.27 1.27)
				)
			)
		)
		(duplicate_pad_numbers_are_jumpers no)
		(fp_line
			(start -0.7874 -0.4064)
			(end 0.7874 -0.4064)
			(stroke
				(width 0.1524)
				(type default)
			)
			(layer "F.SilkS")
		)
		(fp_line
			(start -0.7874 0.4064)
			(end -0.7874 -0.4064)
			(stroke
				(width 0.1524)
				(type default)
			)
			(layer "F.SilkS")
		)
		(fp_line
			(start 0.7874 -0.4064)
			(end 0.7874 0.4064)
			(stroke
				(width 0.1524)
				(type default)
			)
			(layer "F.SilkS")
		)
		(fp_line
			(start 0.7874 0.4064)
			(end -0.7874 0.4064)
			(stroke
				(width 0.1524)
				(type default)
			)
			(layer "F.SilkS")
		)
		(fp_line
			(start -0.67945 -0.305054)
			(end -0.12065 -0.305054)
			(stroke
				(width 0.1)
				(type default)
			)
			(layer "F.Fab")
		)
		(fp_line
			(start -0.67945 0.3048)
			(end -0.67945 -0.305054)
			(stroke
				(width 0.1)
				(type default)
			)
			(layer "F.Fab")
		)
		(fp_line
			(start -0.12065 -0.305054)
			(end -0.12065 -0.2794)
			(stroke
				(width 0.1)
				(type default)
			)
			(layer "F.Fab")
		)
		(fp_line
			(start -0.12065 -0.2794)
			(end 0.12065 -0.2794)
			(stroke
				(width 0.1)
				(type default)
			)
			(layer "F.Fab")
		)
		(fp_line
			(start -0.12065 0.2794)
			(end -0.12065 0.3048)
			(stroke
				(width 0.1)
				(type default)
			)
			(layer "F.Fab")
		)
		(fp_line
			(start -0.12065 0.3048)
			(end -0.67945 0.3048)
			(stroke
				(width 0.1)
				(type default)
			)
			(layer "F.Fab")
		)
		(fp_line
			(start 0.120396 0.2794)
			(end -0.12065 0.2794)
			(stroke
				(width 0.1)
				(type default)
			)
			(layer "F.Fab")
		)
		(fp_line
			(start 0.120396 0.3048)
			(end 0.120396 0.2794)
			(stroke
				(width 0.1)
				(type default)
			)
			(layer "F.Fab")
		)
		(fp_line
			(start 0.12065 -0.3048)
			(end 0.67945 -0.3048)
			(stroke
				(width 0.1)
				(type default)
			)
			(layer "F.Fab")
		)
		(fp_line
			(start 0.12065 -0.2794)
			(end 0.12065 -0.3048)
			(stroke
				(width 0.1)
				(type default)
			)
			(layer "F.Fab")
		)
		(fp_line
			(start 0.67945 -0.3048)
			(end 0.67945 0.3048)
			(stroke
				(width 0.1)
				(type default)
			)
			(layer "F.Fab")
		)
		(fp_line
			(start 0.67945 0.3048)
			(end 0.120396 0.3048)
			(stroke
				(width 0.1)
				(type default)
			)
			(layer "F.Fab")
		)
		(pad "1" smd circle
			(at -0.40005 0)
			(size 0 0)
			(layers "F.Cu" "F.Mask" "F.Paste")
			(net "JTAG_DBP_TMS")
		)
		(pad "2" smd circle
			(at 0.40005 0)
			(size 0 0)
			(layers "F.Cu" "F.Mask" "F.Paste")
			(net "JTAG_DBP_TMS_PCH")
		)
	)
	(footprint ""
		(layer "F.Cu")
		(at 400.558 -152.339548)
		(property "Reference" "PC2180"
			(at 0 0 0)
			(layer "F.SilkS")
			(hide yes)
			(effects
				(font
					(size 1.27 1.27)
				)
			)
		)
		(property "Value" ""
			(at 0 0 0)
			(layer "F.Fab")
			(effects
				(font
					(size 1.27 1.27)
				)
			)
		)
		(duplicate_pad_numbers_are_jumpers no)
		(fp_line
			(start 2.750058 0.999998)
			(end -2.750058 0.999998)
			(stroke
				(width 0.1524)
				(type default)
			)
			(layer "F.SilkS")
		)
		(fp_circle
			(center 0 0.999998)
			(end 2.750058 0.999998)
			(stroke
				(width 0.1524)
				(type default)
			)
			(fill no)
			(layer "F.SilkS")
		)
		(fp_poly
			(pts
				(arc
					(start 2.750058 0.999998)
					(mid 0 3.750056)
					(end -2.750058 0.999998)
				)
			)
			(stroke
				(width 0)
				(type default)
			)
			(fill yes)
			(layer "F.SilkS")
		)
		(fp_circle
			(center 0 0.999998)
			(end 2.750058 0.999998)
			(stroke
				(width 0.1)
				(type default)
			)
			(fill no)
			(layer "F.Fab")
		)
		(pad "1" thru_hole rect
			(at 0 0)
			(size 1.5748 1.5748)
			(drill 1.0668)
			(layers "*.Cu" "*.Mask")
			(remove_unused_layers no)
			(net "PVCCFA_EHV_CPU0")
			(clearance 0)
			(padstack
				(mode front_inner_back)
				(layer "Inner"
					(shape circle)
					(size 1.5748 1.5748)
					(clearance 0)
				)
				(layer "B.Cu"
					(shape rect)
					(size 1.5748 1.5748)
					(clearance 0)
				)
			)
		)
		(pad "2" thru_hole circle
			(at 0 1.999996)
			(size 1.5748 1.5748)
			(drill 1.0668)
			(layers "*.Cu" "*.Mask")
			(remove_unused_layers no)
			(net "GND")
			(clearance 0)
		)
	)
)
